(kicad_pcb
	(version 20260206)
	(generator "pcbnew")
	(generator_version "10.0")
	(general
		(thickness 1.6)
		(legacy_teardrops no)
	)
	(paper "A4")
	(title_block
		(title "m-2 — Lightning_M.2_BRD.brd")
		(comment 1 "Lightning (Wiwynn / Facebook NVMe JBOF) / footprints 17-24 of 157")
	)
	(layers
		(0 "F.Cu" signal "TOP")
		(4 "In1.Cu" signal "L2GND")
		(6 "In2.Cu" signal "L3")
		(8 "In3.Cu" signal "L4GND")
		(10 "In4.Cu" signal "L5GND")
		(12 "In5.Cu" signal "L6")
		(14 "In6.Cu" signal "L7GND")
		(2 "B.Cu" signal "BOTTOM")
		(9 "F.Adhes" user "F.Adhesive")
		(11 "B.Adhes" user "B.Adhesive")
		(13 "F.Paste" user "Package Geometry/Pastemask Top")
		(15 "B.Paste" user "Package Geometry/Pastemask Bottom")
		(5 "F.SilkS" user "Ref Des/Silkscreen Top")
		(7 "B.SilkS" user "Ref Des/Silkscreen Bottom")
		(1 "F.Mask" user "Board Geometry/Soldermask Top")
		(3 "B.Mask" user "Board Geometry/Soldermask Bottom")
		(17 "Dwgs.User" user "User.Drawings")
		(19 "Cmts.User" user "User.Comments")
		(21 "Eco1.User" user "User.Eco1")
		(23 "Eco2.User" user "User.Eco2")
		(25 "Edge.Cuts" user "Board Geometry/Outline")
		(27 "Margin" user)
		(31 "F.CrtYd" user "Package Geometry/Place Bound Top")
		(29 "B.CrtYd" user "Package Geometry/Place Bound Bottom")
		(35 "F.Fab" user "Ref Des/Assembly Top")
		(33 "B.Fab" user "Ref Des/Assembly Bottom")
	)
	(footprint ""
		(layer "F.Cu")
		(at 15.748 -86.154006)
		(property "Reference" "PR18"
			(at 0 0 0)
			(layer "F.SilkS")
			(hide yes)
			(effects
				(font
					(size 1.27 1.27)
				)
			)
		)
		(property "Value" "0R2J-2-GP"
			(at 0.064008 -3.993896 0)
			(unlocked yes)
			(layer "F.Fab")
			(hide yes)
			(effects
				(font
					(size 1.016 1.016)
					(thickness 0.1524)
				)
			)
		)
		(property "Device Type" "R402H16"
			(at 0.064008 -5.517896 0)
			(unlocked yes)
			(layer "F.Fab")
			(hide yes)
			(effects
				(font
					(size 1.016 1.016)
					(thickness 0.1524)
				)
			)
		)
		(duplicate_pad_numbers_are_jumpers no)
		(fp_line
			(start -0.508 -0.9398)
			(end -0.508 0.9398)
			(stroke
				(width 0.1524)
				(type default)
			)
			(layer "F.SilkS")
		)
		(fp_line
			(start 0.508 -0.9398)
			(end -0.508 -0.9398)
			(stroke
				(width 0.1524)
				(type default)
			)
			(layer "F.SilkS")
		)
		(fp_rect
			(start -0.508 0.9398)
			(end 0.508 -0.9398)
			(stroke
				(width 0)
				(type default)
			)
			(fill no)
			(layer "F.CrtYd")
		)
		(fp_rect
			(start -0.508 0.9398)
			(end 0.508 -0.9398)
			(stroke
				(width 0)
				(type default)
			)
			(fill no)
			(layer "F.Fab")
		)
		(pad "1" smd custom
			(at 0 -0.4445)
			(size 0.1397 0.1397)
			(layers "F.Cu" "F.Mask" "F.Paste")
			(net "P3V3_PWR")
			(options
				(clearance outline)
				(anchor circle)
			)
			(primitives
				(gr_poly
					(pts
						(arc
							(start -0.1778 -0.2794)
							(mid -0.249642 -0.249642)
							(end -0.2794 -0.1778)
						)
						(arc
							(start -0.2794 0.1778)
							(mid -0.249642 0.249642)
							(end -0.1778 0.2794)
						)
						(arc
							(start 0.1778 0.2794)
							(mid 0.249642 0.249642)
							(end 0.2794 0.1778)
						)
						(arc
							(start 0.2794 -0.1778)
							(mid 0.249642 -0.249642)
							(end 0.1778 -0.2794)
						)
					)
					(width 0)
					(fill yes)
				)
			)
		)
		(pad "2" smd custom
			(at 0 0.4445)
			(size 0.1397 0.1397)
			(layers "F.Cu" "F.Mask" "F.Paste")
			(net "P1V8_PWR_BIAS")
			(options
				(clearance outline)
				(anchor circle)
			)
			(primitives
				(gr_poly
					(pts
						(arc
							(start -0.1778 -0.2794)
							(mid -0.249642 -0.249642)
							(end -0.2794 -0.1778)
						)
						(arc
							(start -0.2794 0.1778)
							(mid -0.249642 0.249642)
							(end -0.1778 0.2794)
						)
						(arc
							(start 0.1778 0.2794)
							(mid 0.249642 0.249642)
							(end 0.2794 0.1778)
						)
						(arc
							(start 0.2794 -0.1778)
							(mid 0.249642 -0.249642)
							(end 0.1778 -0.2794)
						)
					)
					(width 0)
					(fill yes)
				)
			)
		)
	)
	(footprint ""
		(layer "F.Cu")
		(at 59.817 -18.034 -90)
		(property "Reference" "C20"
			(at 0 0 270)
			(layer "F.SilkS")
			(hide yes)
			(effects
				(font
					(size 1.27 1.27)
				)
			)
		)
		(property "Value" "SC1U6D3V2KX-9-GP"
			(at 1.1811 -2.7051 270)
			(unlocked yes)
			(layer "F.Fab")
			(hide yes)
			(effects
				(font
					(size 1.016 1.016)
					(thickness 0.1524)
				)
			)
		)
		(property "Device Type" "C402H22"
			(at 1.1811 -4.2291 270)
			(unlocked yes)
			(layer "F.Fab")
			(hide yes)
			(effects
				(font
					(size 1.016 1.016)
					(thickness 0.1524)
				)
			)
		)
		(duplicate_pad_numbers_are_jumpers no)
		(fp_rect
			(start -0.4318 0.9525)
			(end 0.4318 -0.9525)
			(stroke
				(width 0)
				(type default)
			)
			(fill no)
			(layer "F.CrtYd")
		)
		(fp_rect
			(start -0.4318 0.9525)
			(end 0.4318 -0.9525)
			(stroke
				(width 0)
				(type default)
			)
			(fill no)
			(layer "F.Fab")
		)
		(pad "1" smd custom
			(at 0 -0.4445 270)
			(size 0.1524 0.1524)
			(layers "F.Cu" "F.Mask" "F.Paste")
			(net "P3V3_PWR")
			(options
				(clearance outline)
				(anchor circle)
			)
			(primitives
				(gr_poly
					(pts
						(arc
							(start 0.3048 -0.2032)
							(mid 0.275042 -0.275042)
							(end 0.2032 -0.3048)
						)
						(arc
							(start -0.2032 -0.3048)
							(mid -0.275042 -0.275042)
							(end -0.3048 -0.2032)
						)
						(arc
							(start -0.3048 0.2032)
							(mid -0.275042 0.275042)
							(end -0.2032 0.3048)
						)
						(arc
							(start 0.2032 0.3048)
							(mid 0.275042 0.275042)
							(end 0.3048 0.2032)
						)
					)
					(width 0)
					(fill yes)
				)
			)
		)
		(pad "2" smd custom
			(at 0 0.4445 270)
			(size 0.1524 0.1524)
			(layers "F.Cu" "F.Mask" "F.Paste")
			(net "GND")
			(options
				(clearance outline)
				(anchor circle)
			)
			(primitives
				(gr_poly
					(pts
						(arc
							(start 0.3048 -0.2032)
							(mid 0.275042 -0.275042)
							(end 0.2032 -0.3048)
						)
						(arc
							(start -0.2032 -0.3048)
							(mid -0.275042 -0.275042)
							(end -0.3048 -0.2032)
						)
						(arc
							(start -0.3048 0.2032)
							(mid -0.275042 0.275042)
							(end -0.2032 0.3048)
						)
						(arc
							(start 0.2032 0.3048)
							(mid 0.275042 0.275042)
							(end 0.3048 0.2032)
						)
					)
					(width 0)
					(fill yes)
				)
			)
		)
	)
	(footprint ""
		(layer "F.Cu")
		(at 59.817 -46.609 -90)
		(property "Reference" "C2"
			(at 0 0 270)
			(layer "F.SilkS")
			(hide yes)
			(effects
				(font
					(size 1.27 1.27)
				)
			)
		)
		(property "Value" "SCD1U16V2KX-3GP"
			(at 1.1811 -2.7051 270)
			(unlocked yes)
			(layer "F.Fab")
			(hide yes)
			(effects
				(font
					(size 1.016 1.016)
					(thickness 0.1524)
				)
			)
		)
		(property "Device Type" "C402H22"
			(at 1.1811 -4.2291 270)
			(unlocked yes)
			(layer "F.Fab")
			(hide yes)
			(effects
				(font
					(size 1.016 1.016)
					(thickness 0.1524)
				)
			)
		)
		(duplicate_pad_numbers_are_jumpers no)
		(fp_rect
			(start -0.4318 0.9525)
			(end 0.4318 -0.9525)
			(stroke
				(width 0)
				(type default)
			)
			(fill no)
			(layer "F.CrtYd")
		)
		(fp_rect
			(start -0.4318 0.9525)
			(end 0.4318 -0.9525)
			(stroke
				(width 0)
				(type default)
			)
			(fill no)
			(layer "F.Fab")
		)
		(pad "1" smd custom
			(at 0 -0.4445 270)
			(size 0.1524 0.1524)
			(layers "F.Cu" "F.Mask" "F.Paste")
			(net "P3V3_PWR")
			(options
				(clearance outline)
				(anchor circle)
			)
			(primitives
				(gr_poly
					(pts
						(arc
							(start 0.3048 -0.2032)
							(mid 0.275042 -0.275042)
							(end 0.2032 -0.3048)
						)
						(arc
							(start -0.2032 -0.3048)
							(mid -0.275042 -0.275042)
							(end -0.3048 -0.2032)
						)
						(arc
							(start -0.3048 0.2032)
							(mid -0.275042 0.275042)
							(end -0.2032 0.3048)
						)
						(arc
							(start 0.2032 0.3048)
							(mid 0.275042 0.275042)
							(end 0.3048 0.2032)
						)
					)
					(width 0)
					(fill yes)
				)
			)
		)
		(pad "2" smd custom
			(at 0 0.4445 270)
			(size 0.1524 0.1524)
			(layers "F.Cu" "F.Mask" "F.Paste")
			(net "GND")
			(options
				(clearance outline)
				(anchor circle)
			)
			(primitives
				(gr_poly
					(pts
						(arc
							(start 0.3048 -0.2032)
							(mid 0.275042 -0.275042)
							(end 0.2032 -0.3048)
						)
						(arc
							(start -0.2032 -0.3048)
							(mid -0.275042 -0.275042)
							(end -0.3048 -0.2032)
						)
						(arc
							(start -0.3048 0.2032)
							(mid -0.275042 0.275042)
							(end -0.2032 0.3048)
						)
						(arc
							(start 0.2032 0.3048)
							(mid 0.275042 0.275042)
							(end 0.3048 0.2032)
						)
					)
					(width 0)
					(fill yes)
				)
			)
		)
	)
	(footprint ""
		(layer "F.Cu")
		(at 59.817 -33.02 -90)
		(property "Reference" "C34"
			(at 0 0 270)
			(layer "F.SilkS")
			(hide yes)
			(effects
				(font
					(size 1.27 1.27)
				)
			)
		)
		(property "Value" "SCD1U16V2KX-3GP"
			(at 1.1811 -2.7051 270)
			(unlocked yes)
			(layer "F.Fab")
			(hide yes)
			(effects
				(font
					(size 1.016 1.016)
					(thickness 0.1524)
				)
			)
		)
		(property "Device Type" "C402H22"
			(at 1.1811 -4.2291 270)
			(unlocked yes)
			(layer "F.Fab")
			(hide yes)
			(effects
				(font
					(size 1.016 1.016)
					(thickness 0.1524)
				)
			)
		)
		(duplicate_pad_numbers_are_jumpers no)
		(fp_rect
			(start -0.4318 0.9525)
			(end 0.4318 -0.9525)
			(stroke
				(width 0)
				(type default)
			)
			(fill no)
			(layer "F.CrtYd")
		)
		(fp_rect
			(start -0.4318 0.9525)
			(end 0.4318 -0.9525)
			(stroke
				(width 0)
				(type default)
			)
			(fill no)
			(layer "F.Fab")
		)
		(pad "1" smd custom
			(at 0 -0.4445 270)
			(size 0.1524 0.1524)
			(layers "F.Cu" "F.Mask" "F.Paste")
			(net "P3V3_PWR")
			(options
				(clearance outline)
				(anchor circle)
			)
			(primitives
				(gr_poly
					(pts
						(arc
							(start 0.3048 -0.2032)
							(mid 0.275042 -0.275042)
							(end 0.2032 -0.3048)
						)
						(arc
							(start -0.2032 -0.3048)
							(mid -0.275042 -0.275042)
							(end -0.3048 -0.2032)
						)
						(arc
							(start -0.3048 0.2032)
							(mid -0.275042 0.275042)
							(end -0.2032 0.3048)
						)
						(arc
							(start 0.2032 0.3048)
							(mid 0.275042 0.275042)
							(end 0.3048 0.2032)
						)
					)
					(width 0)
					(fill yes)
				)
			)
		)
		(pad "2" smd custom
			(at 0 0.4445 270)
			(size 0.1524 0.1524)
			(layers "F.Cu" "F.Mask" "F.Paste")
			(net "GND")
			(options
				(clearance outline)
				(anchor circle)
			)
			(primitives
				(gr_poly
					(pts
						(arc
							(start 0.3048 -0.2032)
							(mid 0.275042 -0.275042)
							(end 0.2032 -0.3048)
						)
						(arc
							(start -0.2032 -0.3048)
							(mid -0.275042 -0.275042)
							(end -0.3048 -0.2032)
						)
						(arc
							(start -0.3048 0.2032)
							(mid -0.275042 0.275042)
							(end -0.2032 0.3048)
						)
						(arc
							(start 0.2032 0.3048)
							(mid 0.275042 0.275042)
							(end 0.3048 0.2032)
						)
					)
					(width 0)
					(fill yes)
				)
			)
		)
	)
	(footprint ""
		(layer "F.Cu")
		(at 39.37 -84.582 180)
		(property "Reference" "PC33"
			(at 0 0 180)
			(layer "F.SilkS")
			(hide yes)
			(effects
				(font
					(size 1.27 1.27)
				)
			)
		)
		(property "Value" "SC10U16V5KX-1-GP"
			(at -0.0762 -6.1214 180)
			(unlocked yes)
			(layer "F.Fab")
			(hide yes)
			(effects
				(font
					(size 1.016 1.016)
					(thickness 0.1524)
				)
			)
		)
		(property "Device Type" "C805H54"
			(at -0.0762 -8.1534 180)
			(unlocked yes)
			(layer "F.Fab")
			(hide yes)
			(effects
				(font
					(size 1.016 1.016)
					(thickness 0.1524)
				)
			)
		)
		(duplicate_pad_numbers_are_jumpers no)
		(fp_line
			(start 0.635 0)
			(end -0.635 0)
			(stroke
				(width 0.508)
				(type default)
			)
			(layer "F.SilkS")
		)
		(fp_rect
			(start -0.9652 1.778)
			(end 0.9652 -1.778)
			(stroke
				(width 0)
				(type default)
			)
			(fill no)
			(layer "F.CrtYd")
		)
		(fp_poly
			(pts
				(xy -0.9652 -1.778) (xy 0.9652 -1.778) (xy 0.9652 1.778) (xy -0.9652 1.778)
			)
			(stroke
				(width 0)
				(type default)
			)
			(fill no)
			(layer "F.Fab")
		)
		(pad "1" smd rect
			(at 0 -0.9652 180)
			(size 1.397 1.143)
			(layers "F.Cu" "F.Mask" "F.Paste")
			(net "P3V3_DEV_VIN")
		)
		(pad "2" smd rect
			(at 0 0.9652 180)
			(size 1.397 1.143)
			(layers "F.Cu" "F.Mask" "F.Paste")
			(net "GND")
		)
	)
	(footprint ""
		(layer "F.Cu")
		(at 59.817 -59.563 -90)
		(property "Reference" "C18"
			(at 0 0 270)
			(layer "F.SilkS")
			(hide yes)
			(effects
				(font
					(size 1.27 1.27)
				)
			)
		)
		(property "Value" "SC1U6D3V2KX-9-GP"
			(at 1.1811 -2.7051 270)
			(unlocked yes)
			(layer "F.Fab")
			(hide yes)
			(effects
				(font
					(size 1.016 1.016)
					(thickness 0.1524)
				)
			)
		)
		(property "Device Type" "C402H22"
			(at 1.1811 -4.2291 270)
			(unlocked yes)
			(layer "F.Fab")
			(hide yes)
			(effects
				(font
					(size 1.016 1.016)
					(thickness 0.1524)
				)
			)
		)
		(duplicate_pad_numbers_are_jumpers no)
		(fp_rect
			(start -0.4318 0.9525)
			(end 0.4318 -0.9525)
			(stroke
				(width 0)
				(type default)
			)
			(fill no)
			(layer "F.CrtYd")
		)
		(fp_rect
			(start -0.4318 0.9525)
			(end 0.4318 -0.9525)
			(stroke
				(width 0)
				(type default)
			)
			(fill no)
			(layer "F.Fab")
		)
		(pad "1" smd custom
			(at 0 -0.4445 270)
			(size 0.1524 0.1524)
			(layers "F.Cu" "F.Mask" "F.Paste")
			(net "P3V3_PWR")
			(options
				(clearance outline)
				(anchor circle)
			)
			(primitives
				(gr_poly
					(pts
						(arc
							(start 0.3048 -0.2032)
							(mid 0.275042 -0.275042)
							(end 0.2032 -0.3048)
						)
						(arc
							(start -0.2032 -0.3048)
							(mid -0.275042 -0.275042)
							(end -0.3048 -0.2032)
						)
						(arc
							(start -0.3048 0.2032)
							(mid -0.275042 0.275042)
							(end -0.2032 0.3048)
						)
						(arc
							(start 0.2032 0.3048)
							(mid 0.275042 0.275042)
							(end 0.3048 0.2032)
						)
					)
					(width 0)
					(fill yes)
				)
			)
		)
		(pad "2" smd custom
			(at 0 0.4445 270)
			(size 0.1524 0.1524)
			(layers "F.Cu" "F.Mask" "F.Paste")
			(net "GND")
			(options
				(clearance outline)
				(anchor circle)
			)
			(primitives
				(gr_poly
					(pts
						(arc
							(start 0.3048 -0.2032)
							(mid 0.275042 -0.275042)
							(end 0.2032 -0.3048)
						)
						(arc
							(start -0.2032 -0.3048)
							(mid -0.275042 -0.275042)
							(end -0.3048 -0.2032)
						)
						(arc
							(start -0.3048 0.2032)
							(mid -0.275042 0.275042)
							(end -0.2032 0.3048)
						)
						(arc
							(start 0.2032 0.3048)
							(mid 0.275042 0.275042)
							(end 0.3048 0.2032)
						)
					)
					(width 0)
					(fill yes)
				)
			)
		)
	)
	(footprint ""
		(layer "F.Cu")
		(at 25.908 -78.74 90)
		(property "Reference" "C8"
			(at 0 0 90)
			(layer "F.SilkS")
			(hide yes)
			(effects
				(font
					(size 1.27 1.27)
				)
			)
		)
		(property "Value" "SCD1U16V2KX-3GP"
			(at 1.1811 -2.7051 90)
			(unlocked yes)
			(layer "F.Fab")
			(hide yes)
			(effects
				(font
					(size 1.016 1.016)
					(thickness 0.1524)
				)
			)
		)
		(property "Device Type" "C402H22"
			(at 1.1811 -4.2291 90)
			(unlocked yes)
			(layer "F.Fab")
			(hide yes)
			(effects
				(font
					(size 1.016 1.016)
					(thickness 0.1524)
				)
			)
		)
		(duplicate_pad_numbers_are_jumpers no)
		(fp_rect
			(start -0.4318 0.9525)
			(end 0.4318 -0.9525)
			(stroke
				(width 0)
				(type default)
			)
			(fill no)
			(layer "F.CrtYd")
		)
		(fp_rect
			(start -0.4318 0.9525)
			(end 0.4318 -0.9525)
			(stroke
				(width 0)
				(type default)
			)
			(fill no)
			(layer "F.Fab")
		)
		(pad "1" smd custom
			(at 0 -0.4445 90)
			(size 0.1524 0.1524)
			(layers "F.Cu" "F.Mask" "F.Paste")
			(net "P1V8_PWR")
			(options
				(clearance outline)
				(anchor circle)
			)
			(primitives
				(gr_poly
					(pts
						(arc
							(start 0.3048 -0.2032)
							(mid 0.275042 -0.275042)
							(end 0.2032 -0.3048)
						)
						(arc
							(start -0.2032 -0.3048)
							(mid -0.275042 -0.275042)
							(end -0.3048 -0.2032)
						)
						(arc
							(start -0.3048 0.2032)
							(mid -0.275042 0.275042)
							(end -0.2032 0.3048)
						)
						(arc
							(start 0.2032 0.3048)
							(mid 0.275042 0.275042)
							(end 0.3048 0.2032)
						)
					)
					(width 0)
					(fill yes)
				)
			)
		)
		(pad "2" smd custom
			(at 0 0.4445 90)
			(size 0.1524 0.1524)
			(layers "F.Cu" "F.Mask" "F.Paste")
			(net "GND")
			(options
				(clearance outline)
				(anchor circle)
			)
			(primitives
				(gr_poly
					(pts
						(arc
							(start 0.3048 -0.2032)
							(mid 0.275042 -0.275042)
							(end 0.2032 -0.3048)
						)
						(arc
							(start -0.2032 -0.3048)
							(mid -0.275042 -0.275042)
							(end -0.3048 -0.2032)
						)
						(arc
							(start -0.3048 0.2032)
							(mid -0.275042 0.275042)
							(end -0.2032 0.3048)
						)
						(arc
							(start 0.2032 0.3048)
							(mid 0.275042 0.275042)
							(end 0.3048 0.2032)
						)
					)
					(width 0)
					(fill yes)
				)
			)
		)
	)
	(footprint ""
		(layer "F.Cu")
		(at 16.51 -74.724006 -90)
		(property "Reference" "PR23"
			(at 0 0 270)
			(layer "F.SilkS")
			(hide yes)
			(effects
				(font
					(size 1.27 1.27)
				)
			)
		)
		(property "Value" "2K87R2F-1-GP"
			(at 0.064008 -3.993896 270)
			(unlocked yes)
			(layer "F.Fab")
			(hide yes)
			(effects
				(font
					(size 1.016 1.016)
					(thickness 0.1524)
				)
			)
		)
		(property "Device Type" "R402H16"
			(at 0.064008 -5.517896 270)
			(unlocked yes)
			(layer "F.Fab")
			(hide yes)
			(effects
				(font
					(size 1.016 1.016)
					(thickness 0.1524)
				)
			)
		)
		(duplicate_pad_numbers_are_jumpers no)
		(fp_line
			(start -0.508 -0.9398)
			(end -0.508 0.9398)
			(stroke
				(width 0.1524)
				(type default)
			)
			(layer "F.SilkS")
		)
		(fp_line
			(start 0.508 -0.9398)
			(end -0.508 -0.9398)
			(stroke
				(width 0.1524)
				(type default)
			)
			(layer "F.SilkS")
		)
		(fp_rect
			(start -0.508 0.9398)
			(end 0.508 -0.9398)
			(stroke
				(width 0)
				(type default)
			)
			(fill no)
			(layer "F.CrtYd")
		)
		(fp_rect
			(start -0.508 0.9398)
			(end 0.508 -0.9398)
			(stroke
				(width 0)
				(type default)
			)
			(fill no)
			(layer "F.Fab")
		)
		(pad "1" smd custom
			(at 0 -0.4445 270)
			(size 0.1397 0.1397)
			(layers "F.Cu" "F.Mask" "F.Paste")
			(net "P1V8_PWR_FB")
			(options
				(clearance outline)
				(anchor circle)
			)
			(primitives
				(gr_poly
					(pts
						(arc
							(start -0.1778 -0.2794)
							(mid -0.249642 -0.249642)
							(end -0.2794 -0.1778)
						)
						(arc
							(start -0.2794 0.1778)
							(mid -0.249642 0.249642)
							(end -0.1778 0.2794)
						)
						(arc
							(start 0.1778 0.2794)
							(mid 0.249642 0.249642)
							(end 0.2794 0.1778)
						)
						(arc
							(start 0.2794 -0.1778)
							(mid 0.249642 -0.249642)
							(end 0.1778 -0.2794)
						)
					)
					(width 0)
					(fill yes)
				)
			)
		)
		(pad "2" smd custom
			(at 0 0.4445 270)
			(size 0.1397 0.1397)
			(layers "F.Cu" "F.Mask" "F.Paste")
			(net "GND")
			(options
				(clearance outline)
				(anchor circle)
			)
			(primitives
				(gr_poly
					(pts
						(arc
							(start -0.1778 -0.2794)
							(mid -0.249642 -0.249642)
							(end -0.2794 -0.1778)
						)
						(arc
							(start -0.2794 0.1778)
							(mid -0.249642 0.249642)
							(end -0.1778 0.2794)
						)
						(arc
							(start 0.1778 0.2794)
							(mid 0.249642 0.249642)
							(end 0.2794 0.1778)
						)
						(arc
							(start 0.2794 -0.1778)
							(mid 0.249642 -0.249642)
							(end 0.1778 -0.2794)
						)
					)
					(width 0)
					(fill yes)
				)
			)
		)
	)
)
